(kicad_pcb
	(version 20241229)
	(generator "pcbnew")
	(generator_version "9.0")
	(general
		(thickness 1.61)
		(legacy_teardrops no)
	)
	(paper "A3")
	(title_block
		(title "RDIMM DDR5 Tester")
		(date "2026-05-21")
		(rev "2.2.0")
		(company "Antmicro")
		(comment 9 "footprints 533-537 of 796")
	)
	(layers
		(0 "F.Cu" signal)
		(4 "In1.Cu" power)
		(6 "In2.Cu" mixed)
		(8 "In3.Cu" power)
		(10 "In4.Cu" mixed)
		(12 "In5.Cu" power)
		(14 "In6.Cu" mixed)
		(16 "In7.Cu" power)
		(18 "In8.Cu" power)
		(20 "In9.Cu" mixed)
		(22 "In10.Cu" power)
		(2 "B.Cu" signal)
		(9 "F.Adhes" user "F.Adhesive")
		(11 "B.Adhes" user "B.Adhesive")
		(13 "F.Paste" user)
		(15 "B.Paste" user)
		(5 "F.SilkS" user "F.Silkscreen")
		(7 "B.SilkS" user "B.Silkscreen")
		(1 "F.Mask" user)
		(3 "B.Mask" user)
		(17 "Dwgs.User" user "User.Drawings")
		(19 "Cmts.User" user "User.Comments")
		(21 "Eco1.User" user "User.Eco1")
		(23 "Eco2.User" user "User.Eco2")
		(25 "Edge.Cuts" user)
		(27 "Margin" user)
		(31 "F.CrtYd" user "F.Courtyard")
		(29 "B.CrtYd" user "B.Courtyard")
		(35 "F.Fab" user)
		(33 "B.Fab" user)
	)
	(footprint "antmicro-footprints:Coax_Conn_U.FL"
		(layer "B.Cu")
		(at 123.89 127.99 -90)
		(descr "https://media.digikey.com/pdf/Data%20Sheets/Hirose%20PDFs/UFL%20Series.pdf")
		(property "Reference" "J13"
			(at 3.11 -2.46 180)
			(layer "B.SilkS")
			(hide yes)
			(effects
				(font
					(size 0.7 0.7)
					(thickness 0.15)
				)
				(justify left bottom mirror)
			)
		)
		(property "Value" "U_FL-R-SMT-1"
			(at -4.13 -2.52 90)
			(layer "B.Fab")
			(effects
				(font
					(size 0.7 0.7)
					(thickness 0.15)
				)
				(justify left bottom mirror)
			)
		)
		(property "Datasheet" "https://media.digikey.com/pdf/Data%20Sheets/Hirose%20PDFs/UFL%20Series.pdf"
			(at 0 0 270)
			(layer "F.Fab")
			(hide yes)
			(effects
				(font
					(size 1.27 1.27)
					(thickness 0.15)
				)
			)
		)
		(property "MPN" "U.FL-R-SMT-1(10)"
			(at 0 0 270)
			(unlocked yes)
			(layer "B.Fab")
			(hide yes)
			(effects
				(font
					(size 1 1)
					(thickness 0.15)
				)
				(justify mirror)
			)
		)
		(property "Manufacturer" "Hirose Electric"
			(at 0 0 270)
			(unlocked yes)
			(layer "B.Fab")
			(hide yes)
			(effects
				(font
					(size 1 1)
					(thickness 0.15)
				)
				(justify mirror)
			)
		)
		(property "Author" "Antmicro"
			(at 0 0 270)
			(unlocked yes)
			(layer "B.Fab")
			(hide yes)
			(effects
				(font
					(size 1 1)
					(thickness 0.15)
				)
				(justify mirror)
			)
		)
		(property "License" "Apache-2.0"
			(at 0 0 270)
			(unlocked yes)
			(layer "B.Fab")
			(hide yes)
			(effects
				(font
					(size 1 1)
					(thickness 0.15)
				)
				(justify mirror)
			)
		)
		(sheetname "/Debug FTDI + VNA/")
		(sheetfile "debug-ftdi.kicad_sch")
		(attr smd)
		(fp_line
			(start -1.613 1.651)
			(end -1.113 1.651)
			(stroke
				(width 0.15)
				(type solid)
			)
			(layer "B.SilkS")
		)
		(fp_line
			(start -1.613 1.651)
			(end -1.613 1.325)
			(stroke
				(width 0.15)
				(type solid)
			)
			(layer "B.SilkS")
		)
		(fp_line
			(start 1.588 1.651)
			(end 1.088 1.651)
			(stroke
				(width 0.15)
				(type solid)
			)
			(layer "B.SilkS")
		)
		(fp_line
			(start 1.588 1.651)
			(end 1.588 1.325)
			(stroke
				(width 0.15)
				(type solid)
			)
			(layer "B.SilkS")
		)
		(fp_line
			(start -1.613 -1.648)
			(end -1.613 -1.325)
			(stroke
				(width 0.15)
				(type solid)
			)
			(layer "B.SilkS")
		)
		(fp_line
			(start -1.613 -1.648)
			(end -1.113 -1.648)
			(stroke
				(width 0.15)
				(type solid)
			)
			(layer "B.SilkS")
		)
		(fp_line
			(start 1.588 -1.648)
			(end 1.588 -1.325)
			(stroke
				(width 0.15)
				(type solid)
			)
			(layer "B.SilkS")
		)
		(fp_line
			(start 1.588 -1.648)
			(end 1.088 -1.648)
			(stroke
				(width 0.15)
				(type solid)
			)
			(layer "B.SilkS")
		)
		(fp_rect
			(start -2 2.051)
			(end 1.999 -2.05)
			(stroke
				(width 0.05)
				(type solid)
			)
			(fill no)
			(layer "B.CrtYd")
		)
		(fp_line
			(start -1.512 1.551)
			(end 1.487 1.551)
			(stroke
				(width 0.15)
				(type solid)
			)
			(layer "B.Fab")
		)
		(fp_line
			(start -1.512 -1.55)
			(end -1.512 1.551)
			(stroke
				(width 0.15)
				(type solid)
			)
			(layer "B.Fab")
		)
		(fp_line
			(start -1.512 -1.55)
			(end 1.487 -1.55)
			(stroke
				(width 0.15)
				(type solid)
			)
			(layer "B.Fab")
		)
		(fp_line
			(start 1.487 -1.55)
			(end 1.487 1.551)
			(stroke
				(width 0.15)
				(type solid)
			)
			(layer "B.Fab")
		)
		(fp_text user "${REFERENCE}"
			(at -4.13 -6.92 90)
			(layer "B.Fab")
			(effects
				(font
					(size 0.7 0.7)
					(thickness 0.15)
				)
				(justify left bottom mirror)
			)
		)
		(fp_text user "License: Apache-2.0"
			(at -4.13 -5.72 90)
			(layer "B.Fab")
			(effects
				(font
					(size 0.7 0.7)
					(thickness 0.15)
				)
				(justify left bottom mirror)
			)
		)
		(fp_text user "Author: Antmicro"
			(at -4.13 -4.52 90)
			(layer "B.Fab")
			(effects
				(font
					(size 0.7 0.7)
					(thickness 0.15)
				)
				(justify left bottom mirror)
			)
		)
		(pad "1" smd rect
			(at -0.012 -1.499 270)
			(size 1 1.05)
			(layers "B.Cu" "B.Mask" "B.Paste")
			(net 1 "GND")
			(pintype "passive")
		)
		(pad "SH1" smd rect
			(at 1.463 0 270)
			(size 1.05 2.2)
			(layers "B.Cu" "B.Mask" "B.Paste")
			(net 1 "GND")
			(pintype "passive")
		)
		(pad "SH2" smd rect
			(at -1.488 0 270)
			(size 1.05 2.2)
			(layers "B.Cu" "B.Mask" "B.Paste")
			(net 1 "GND")
			(pintype "passive")
		)
		(zone
			(net 0)
			(net_name "")
			(layer "B.Cu")
			(hatch edge 0.508)
			(connect_pads
				(clearance 0)
			)
			(min_thickness 0.254)
			(filled_areas_thickness no)
			(keepout
				(tracks not_allowed)
				(vias not_allowed)
				(pads not_allowed)
				(copperpour not_allowed)
				(footprints not_allowed)
			)
			(placement
				(enabled no)
				(sheetname "")
			)
			(fill
				(thermal_gap 0.508)
				(thermal_bridge_width 0.508)
			)
			(polygon
				(pts
					(xy 124.85 128.92) (xy 124.85 127.04) (xy 122.79 127.04) (xy 122.79 128.92)
				)
			)
		)
	)
	(footprint "antmicro-footprints:R_0402_1005Metric"
		(layer "B.Cu")
		(at 115.397499 119.149 180)
		(descr "Resistor SMD 0402")
		(tags "resistor SMD 0402")
		(property "Reference" "R193"
			(at -4.102501 -0.151 0)
			(layer "B.SilkS")
			(effects
				(font
					(size 0.7 0.7)
					(thickness 0.15)
				)
				(justify left bottom mirror)
			)
		)
		(property "Value" "R_330R_0402"
			(at -1.011843 -1.772047 0)
			(layer "B.Fab")
			(effects
				(font
					(size 0.7 0.7)
					(thickness 0.15)
				)
				(justify left bottom mirror)
			)
		)
		(property "Datasheet" "https://www.bourns.com/docs/product-datasheets/cr.pdf"
			(at 0 0 180)
			(layer "F.Fab")
			(hide yes)
			(effects
				(font
					(size 1.27 1.27)
					(thickness 0.15)
				)
			)
		)
		(property "Manufacturer" "Bourns"
			(at 0 0 180)
			(unlocked yes)
			(layer "B.Fab")
			(hide yes)
			(effects
				(font
					(size 1 1)
					(thickness 0.15)
				)
				(justify mirror)
			)
		)
		(property "MPN" "CR0402-FX-3300GLF"
			(at 0 0 180)
			(unlocked yes)
			(layer "B.Fab")
			(hide yes)
			(effects
				(font
					(size 1 1)
					(thickness 0.15)
				)
				(justify mirror)
			)
		)
		(property "Val" "330R"
			(at 0 0 180)
			(unlocked yes)
			(layer "B.Fab")
			(hide yes)
			(effects
				(font
					(size 1 1)
					(thickness 0.15)
				)
				(justify mirror)
			)
		)
		(property "License" "Apache-2.0"
			(at 0 0 180)
			(unlocked yes)
			(layer "B.Fab")
			(hide yes)
			(effects
				(font
					(size 1 1)
					(thickness 0.15)
				)
				(justify mirror)
			)
		)
		(property "Author" "Antmicro"
			(at 0 0 180)
			(unlocked yes)
			(layer "B.Fab")
			(hide yes)
			(effects
				(font
					(size 1 1)
					(thickness 0.15)
				)
				(justify mirror)
			)
		)
		(property "Tolerance" "1%"
			(at 0 0 180)
			(unlocked yes)
			(layer "B.Fab")
			(hide yes)
			(effects
				(font
					(size 1 1)
					(thickness 0.15)
				)
				(justify mirror)
			)
		)
		(sheetname "/Ethernet/")
		(sheetfile "ethernet.kicad_sch")
		(attr smd)
		(fp_rect
			(start -0.925 0.47)
			(end 0.925 -0.47)
			(stroke
				(width 0.05)
				(type default)
			)
			(fill no)
			(layer "B.CrtYd")
		)
		(fp_rect
			(start -0.5 0.25)
			(end 0.5 -0.25)
			(stroke
				(width 0.15)
				(type solid)
			)
			(fill no)
			(layer "B.Fab")
		)
		(fp_text user "License: Apache-2.0"
			(at -0.95 -5.169 0)
			(layer "B.Fab")
			(effects
				(font
					(size 0.7 0.7)
					(thickness 0.15)
				)
				(justify left bottom mirror)
			)
		)
		(fp_text user "Author: Antmicro"
			(at -0.95 -4.169 0)
			(layer "B.Fab")
			(effects
				(font
					(size 0.7 0.7)
					(thickness 0.15)
				)
				(justify left bottom mirror)
			)
		)
		(fp_text user "${REFERENCE}"
			(at -0.95 -3.168 0)
			(layer "B.Fab")
			(effects
				(font
					(size 0.7 0.7)
					(thickness 0.15)
				)
				(justify left bottom mirror)
			)
		)
		(pad "1" smd roundrect
			(at -0.48 0 180)
			(size 0.59 0.64)
			(layers "B.Cu" "B.Mask" "B.Paste")
			(roundrect_rratio 0.25)
			(net 1 "GND")
			(pintype "passive")
		)
		(pad "2" smd roundrect
			(at 0.48 0 180)
			(size 0.59 0.64)
			(layers "B.Cu" "B.Mask" "B.Paste")
			(roundrect_rratio 0.25)
			(net 31 "Net-(C234-Pad1)")
			(pintype "passive")
		)
	)
	(footprint "antmicro-footprints:NetTie-2_SMD_Pad0.127mm"
		(layer "B.Cu")
		(at 221.635 176.66 90)
		(descr "Net tie, 2 pin, 0.127mm  SMD pads")
		(tags "net tie")
		(property "Reference" "TP23"
			(at 1.11 -0.735 90)
			(layer "B.SilkS")
			(hide yes)
			(effects
				(font
					(size 0.7 0.7)
					(thickness 0.15)
				)
				(justify right bottom mirror)
			)
		)
		(property "Value" "Net-Tie_P0.127mm"
			(at 0 -1.199 90)
			(layer "B.Fab")
			(effects
				(font
					(size 0.7 0.7)
					(thickness 0.15)
				)
				(justify right bottom mirror)
			)
		)
		(property "MPN" ""
			(at 0 0 90)
			(unlocked yes)
			(layer "B.Fab")
			(hide yes)
			(effects
				(font
					(size 1 1)
					(thickness 0.15)
				)
				(justify mirror)
			)
		)
		(property "Manufacturer" ""
			(at 0 0 90)
			(unlocked yes)
			(layer "B.Fab")
			(hide yes)
			(effects
				(font
					(size 1 1)
					(thickness 0.15)
				)
				(justify mirror)
			)
		)
		(property "Author" "Antmicro"
			(at 0 0 90)
			(unlocked yes)
			(layer "B.Fab")
			(hide yes)
			(effects
				(font
					(size 1 1)
					(thickness 0.15)
				)
				(justify mirror)
			)
		)
		(property "License" "Apache-2.0"
			(at 0 0 90)
			(unlocked yes)
			(layer "B.Fab")
			(hide yes)
			(effects
				(font
					(size 1 1)
					(thickness 0.15)
				)
				(justify mirror)
			)
		)
		(property ki_fp_filters "Net*Tie*")
		(sheetname "/Supply/DC-DC VCCINT/")
		(sheetfile "dc-dc-vccint.kicad_sch")
		(attr through_hole exclude_from_pos_files exclude_from_bom)
		(net_tie_pad_groups "1, 2")
		(fp_poly
			(pts
				(xy -0.0635 0.0635) (xy 0.0625 0.0635) (xy 0.0625 -0.0635) (xy -0.0635 -0.0635)
			)
			(stroke
				(width 0)
				(type solid)
			)
			(fill yes)
			(layer "B.Cu")
		)
		(fp_poly
			(pts
				(xy 0.2 0.16) (xy 0.29 0.07) (xy 0.29 -0.07) (xy 0.2 -0.16) (xy -0.2 -0.16) (xy -0.29 -0.07) (xy -0.29 0.06)
				(xy -0.19 0.16)
			)
			(stroke
				(width 0.05)
				(type solid)
			)
			(fill no)
			(layer "B.CrtYd")
		)
		(fp_text user "Author: Antmicro"
			(at -0.128 -4.4 270)
			(layer "B.Fab")
			(effects
				(font
					(size 0.7 0.7)
					(thickness 0.15)
				)
				(justify left bottom mirror)
			)
		)
		(fp_text user "License: Apache-2.0"
			(at -0.128 -5.6 270)
			(layer "B.Fab")
			(effects
				(font
					(size 0.7 0.7)
					(thickness 0.15)
				)
				(justify left bottom mirror)
			)
		)
		(fp_text user "${REFERENCE}"
			(at -0.128 -3.2 270)
			(layer "B.Fab")
			(effects
				(font
					(size 0.7 0.7)
					(thickness 0.15)
				)
				(justify left bottom mirror)
			)
		)
		(pad "1" smd roundrect
			(at -0.127 0 270)
			(size 0.127 0.127)
			(layers "B.Cu")
			(roundrect_rratio 0.5)
			(chamfer_ratio 0)
			(chamfer top_left bottom_left)
			(net 755 "/Supply/DC-DC VCCINT/VREF-")
			(pinfunction "1")
			(pintype "passive")
		)
		(pad "2" smd roundrect
			(at 0.126 0 90)
			(size 0.127 0.127)
			(layers "B.Cu")
			(roundrect_rratio 0.5)
			(chamfer_ratio 0)
			(chamfer top_left bottom_left)
			(net 1 "GND")
			(pinfunction "2")
			(pintype "passive")
		)
	)
	(footprint "antmicro-footprints:R_0402_1005Metric"
		(layer "B.Cu")
		(at 253.039499 143.8)
		(descr "Resistor SMD 0402")
		(tags "resistor SMD 0402")
		(property "Reference" "R87"
			(at -1.139499 1.4 0)
			(layer "B.SilkS")
			(effects
				(font
					(size 0.7 0.7)
					(thickness 0.15)
				)
				(justify right bottom mirror)
			)
		)
		(property "Value" "R_330R_0402"
			(at -1.011843 -1.772047 0)
			(layer "B.Fab")
			(effects
				(font
					(size 0.7 0.7)
					(thickness 0.15)
				)
				(justify right bottom mirror)
			)
		)
		(property "Datasheet" "https://www.bourns.com/docs/product-datasheets/cr.pdf"
			(at 0 0 0)
			(layer "F.Fab")
			(hide yes)
			(effects
				(font
					(size 1.27 1.27)
					(thickness 0.15)
				)
			)
		)
		(property "MPN" "CR0402-FX-3300GLF"
			(at 0 0 0)
			(unlocked yes)
			(layer "B.Fab")
			(hide yes)
			(effects
				(font
					(size 1 1)
					(thickness 0.15)
				)
				(justify mirror)
			)
		)
		(property "Manufacturer" "Bourns"
			(at 0 0 0)
			(unlocked yes)
			(layer "B.Fab")
			(hide yes)
			(effects
				(font
					(size 1 1)
					(thickness 0.15)
				)
				(justify mirror)
			)
		)
		(property "License" "Apache-2.0"
			(at 0 0 0)
			(unlocked yes)
			(layer "B.Fab")
			(hide yes)
			(effects
				(font
					(size 1 1)
					(thickness 0.15)
				)
				(justify mirror)
			)
		)
		(property "Author" "Antmicro"
			(at 0 0 0)
			(unlocked yes)
			(layer "B.Fab")
			(hide yes)
			(effects
				(font
					(size 1 1)
					(thickness 0.15)
				)
				(justify mirror)
			)
		)
		(property "Val" "330R"
			(at 0 0 0)
			(unlocked yes)
			(layer "B.Fab")
			(hide yes)
			(effects
				(font
					(size 1 1)
					(thickness 0.15)
				)
				(justify mirror)
			)
		)
		(property "Tolerance" "1%"
			(at 0 0 0)
			(unlocked yes)
			(layer "B.Fab")
			(hide yes)
			(effects
				(font
					(size 1 1)
					(thickness 0.15)
				)
				(justify mirror)
			)
		)
		(sheetname "/Supply/")
		(sheetfile "supply.kicad_sch")
		(attr smd)
		(fp_rect
			(start -0.925 0.47)
			(end 0.925 -0.47)
			(stroke
				(width 0.05)
				(type default)
			)
			(fill no)
			(layer "B.CrtYd")
		)
		(fp_rect
			(start -0.5 0.25)
			(end 0.5 -0.25)
			(stroke
				(width 0.15)
				(type solid)
			)
			(fill no)
			(layer "B.Fab")
		)
		(fp_text user "${REFERENCE}"
			(at -0.95 -3.168 180)
			(layer "B.Fab")
			(effects
				(font
					(size 0.7 0.7)
					(thickness 0.15)
				)
				(justify left bottom mirror)
			)
		)
		(fp_text user "Author: Antmicro"
			(at -0.95 -4.169 180)
			(layer "B.Fab")
			(effects
				(font
					(size 0.7 0.7)
					(thickness 0.15)
				)
				(justify left bottom mirror)
			)
		)
		(fp_text user "License: Apache-2.0"
			(at -0.95 -5.169 180)
			(layer "B.Fab")
			(effects
				(font
					(size 0.7 0.7)
					(thickness 0.15)
				)
				(justify left bottom mirror)
			)
		)
		(pad "1" smd roundrect
			(at -0.48 0)
			(size 0.59 0.64)
			(layers "B.Cu" "B.Mask" "B.Paste")
			(roundrect_rratio 0.25)
			(net 486 "Net-(R87-Pad1)")
			(pintype "passive")
		)
		(pad "2" smd roundrect
			(at 0.48 0)
			(size 0.59 0.64)
			(layers "B.Cu" "B.Mask" "B.Paste")
			(roundrect_rratio 0.25)
			(net 151 "+3V3")
			(pintype "passive")
		)
	)
	(footprint "antmicro-footprints:C_0402_1005Metric_EIA"
		(layer "B.Cu")
		(at 184 158.5 90)
		(descr "Capacitor SMD 0402 (1005 Metric), square (rectangular) end terminal, IPC_7351 nominal, (Body size source: IPC-SM-782 page 76, https://www.pcb-3d.com/wordpress/wp-content/uploads/ipc-sm-782a_amendment_1_and_2.pdf)")
		(tags "capacitor 0402")
		(property "Reference" "C102"
			(at 9.025 -30.725 90)
			(layer "B.SilkS")
			(effects
				(font
					(size 0.7 0.7)
					(thickness 0.15)
				)
				(justify right bottom mirror)
			)
		)
		(property "Value" "C_4u7_0402"
			(at 0 -1.169 90)
			(layer "B.Fab")
			(effects
				(font
					(size 0.7 0.7)
					(thickness 0.15)
				)
				(justify right bottom mirror)
			)
		)
		(property "Datasheet" "https://www.murata.com/products/productdetail?partno=GRM155R61A475MEAA%23"
			(at 0 0 90)
			(layer "F.Fab")
			(hide yes)
			(effects
				(font
					(size 1.27 1.27)
					(thickness 0.15)
				)
			)
		)
		(property "Manufacturer" "Murata"
			(at 0 0 90)
			(unlocked yes)
			(layer "B.Fab")
			(hide yes)
			(effects
				(font
					(size 1 1)
					(thickness 0.15)
				)
				(justify mirror)
			)
		)
		(property "MPN" "GRM155R61A475MEAAD"
			(at 0 0 90)
			(unlocked yes)
			(layer "B.Fab")
			(hide yes)
			(effects
				(font
					(size 1 1)
					(thickness 0.15)
				)
				(justify mirror)
			)
		)
		(property "Val" "4u7"
			(at 0 0 90)
			(unlocked yes)
			(layer "B.Fab")
			(hide yes)
			(effects
				(font
					(size 1 1)
					(thickness 0.15)
				)
				(justify mirror)
			)
		)
		(property "License" "Apache-2.0"
			(at 0 0 90)
			(unlocked yes)
			(layer "B.Fab")
			(hide yes)
			(effects
				(font
					(size 1 1)
					(thickness 0.15)
				)
				(justify mirror)
			)
		)
		(property "Author" "Antmicro"
			(at 0 0 90)
			(unlocked yes)
			(layer "B.Fab")
			(hide yes)
			(effects
				(font
					(size 1 1)
					(thickness 0.15)
				)
				(justify mirror)
			)
		)
		(property "Voltage" ""
			(at 0 0 90)
			(unlocked yes)
			(layer "B.Fab")
			(hide yes)
			(effects
				(font
					(size 1 1)
					(thickness 0.15)
				)
				(justify mirror)
			)
		)
		(property "Dielectric" ""
			(at 0 0 90)
			(unlocked yes)
			(layer "B.Fab")
			(hide yes)
			(effects
				(font
					(size 1 1)
					(thickness 0.15)
				)
				(justify mirror)
			)
		)
		(sheetname "/FPGA power/")
		(sheetfile "fpga-power.kicad_sch")
		(attr smd)
		(fp_rect
			(start -0.95 0.45)
			(end 0.95 -0.45)
			(stroke
				(width 0.05)
				(type default)
			)
			(fill no)
			(layer "B.CrtYd")
		)
		(fp_line
			(start 0.498 -0.248)
			(end -0.5 -0.248)
			(stroke
				(width 0.15)
				(type solid)
			)
			(layer "B.Fab")
		)
		(fp_line
			(start -0.5 -0.248)
			(end -0.5 0.25)
			(stroke
				(width 0.15)
				(type solid)
			)
			(layer "B.Fab")
		)
		(fp_line
			(start 0.498 0.25)
			(end 0.498 -0.248)
			(stroke
				(width 0.15)
				(type solid)
			)
			(layer "B.Fab")
		)
		(fp_line
			(start -0.5 0.25)
			(end 0.498 0.25)
			(stroke
				(width 0.15)
				(type solid)
			)
			(layer "B.Fab")
		)
		(fp_text user "Author: Antmicro"
			(at -0.9656 -5.569 270)
			(layer "B.Fab")
			(effects
				(font
					(size 0.7 0.7)
					(thickness 0.15)
				)
				(justify left bottom mirror)
			)
		)
		(fp_text user "License: Apache-2.0"
			(at -0.9656 -4.369 270)
			(layer "B.Fab")
			(effects
				(font
					(size 0.7 0.7)
					(thickness 0.15)
				)
				(justify left bottom mirror)
			)
		)
		(fp_text user "${REFERENCE}"
			(at -0.9656 -3.169 270)
			(layer "B.Fab")
			(effects
				(font
					(size 0.7 0.7)
					(thickness 0.15)
				)
				(justify left bottom mirror)
			)
		)
		(pad "1" smd roundrect
			(at -0.5 0)
			(size 0.6 0.6)
			(layers "B.Cu" "B.Mask" "B.Paste")
			(roundrect_rratio 0.25)
			(net 820 "+0V9_MGTAVCC")
			(pintype "passive")
		)
		(pad "2" smd roundrect
			(at 0.498 0 90)
			(size 0.6 0.6)
			(layers "B.Cu" "B.Mask" "B.Paste")
			(roundrect_rratio 0.25)
			(net 1 "GND")
			(pintype "passive")
		)
	)
)
